# SCM (Grand Teton) — schematic netlist excerpt (pin names and nets, part order shuffled) for the footprints in the layout excerpt that follows; sources: Cadence DE-HDL packaged netlist, KiCad conversion of 12092022_DA0F0TMDCD0_F0T_Management_Board_D_brd_V3_OCP.brd

R603  Q_RES  750 1% CHIP  pkg 0402LF  page 47 : A = LED_POSTCODE_1 ; B = LED_POSTCODE_1_R

Q1  MMBT39047F  MMBT3904-7-F IC  pkg SOT23_BEC  page 22
  \1\  = BJT_Q3_C
  \3\  = RST_BMC_EXTRST_R2_N
  \2\  = GND

(kicad_pcb
	(version 20260206)
	(generator "pcbnew")
	(generator_version "10.0")
	(general
		(thickness 1.6)
		(legacy_teardrops no)
	)
	(paper "A4")
	(title_block
		(title "12092022_DA0F0TMDCD0_F0T_Management_Board_D_brd_V3_OCP.brd")
		(comment 1 "Grand Teton / footprints 388-389 of 1440")
	)
	(layers
		(0 "F.Cu" signal "TOP")
		(4 "In1.Cu" signal "GND")
		(6 "In2.Cu" signal "IN1")
		(8 "In3.Cu" signal "GND1")
		(10 "In4.Cu" signal "IN2")
		(12 "In5.Cu" signal "VCC")
		(14 "In6.Cu" signal "VCC1")
		(16 "In7.Cu" signal "IN3")
		(18 "In8.Cu" signal "GND2")
		(20 "In9.Cu" signal "IN4")
		(22 "In10.Cu" signal "GND3")
		(2 "B.Cu" signal "BOTTOM")
		(9 "F.Adhes" user "F.Adhesive")
		(11 "B.Adhes" user "B.Adhesive")
		(13 "F.Paste" user "Package Geometry/Pastemask Top")
		(15 "B.Paste" user "Package Geometry/Pastemask Bottom")
		(5 "F.SilkS" user "Ref Des/Silkscreen Top")
		(7 "B.SilkS" user "Ref Des/Silkscreen Bottom")
		(1 "F.Mask" user "Board Geometry/Soldermask Top")
		(3 "B.Mask" user "Board Geometry/Soldermask Bottom")
		(17 "Dwgs.User" user "User.Drawings")
		(19 "Cmts.User" user "User.Comments")
		(21 "Eco1.User" user "User.Eco1")
		(23 "Eco2.User" user "User.Eco2")
		(25 "Edge.Cuts" user "Board Geometry/Outline")
		(27 "Margin" user)
		(31 "F.CrtYd" user "Package Geometry/Place Bound Top")
		(29 "B.CrtYd" user "Package Geometry/Place Bound Bottom")
		(35 "F.Fab" user "Ref Des/Assembly Top")
		(33 "B.Fab" user "Ref Des/Assembly Bottom")
	)
	(footprint ""
		(layer "F.Cu")
		(at 80.280764 -26.496772 -90)
		(property "Reference" "R603"
			(at 0 0 270)
			(layer "F.SilkS")
			(hide yes)
			(effects
				(font
					(size 1.27 1.27)
				)
			)
		)
		(property "Value" ""
			(at 0 0 270)
			(layer "F.Fab")
			(effects
				(font
					(size 1.27 1.27)
				)
			)
		)
		(duplicate_pad_numbers_are_jumpers no)
		(fp_line
			(start -0.7874 0.4064)
			(end -0.7874 -0.4064)
			(stroke
				(width 0.1524)
				(type default)
			)
			(layer "F.SilkS")
		)
		(fp_line
			(start 0.7874 0.4064)
			(end -0.7874 0.4064)
			(stroke
				(width 0.1524)
				(type default)
			)
			(layer "F.SilkS")
		)
		(fp_line
			(start -0.7874 -0.4064)
			(end 0.7874 -0.4064)
			(stroke
				(width 0.1524)
				(type default)
			)
			(layer "F.SilkS")
		)
		(fp_line
			(start 0.7874 -0.4064)
			(end 0.7874 0.4064)
			(stroke
				(width 0.1524)
				(type default)
			)
			(layer "F.SilkS")
		)
		(fp_line
			(start -0.67945 0.3048)
			(end -0.67945 -0.305054)
			(stroke
				(width 0.1)
				(type default)
			)
			(layer "F.Fab")
		)
		(fp_line
			(start -0.12065 0.3048)
			(end -0.67945 0.3048)
			(stroke
				(width 0.1)
				(type default)
			)
			(layer "F.Fab")
		)
		(fp_line
			(start 0.120396 0.3048)
			(end 0.120396 0.2794)
			(stroke
				(width 0.1)
				(type default)
			)
			(layer "F.Fab")
		)
		(fp_line
			(start 0.67945 0.3048)
			(end 0.120396 0.3048)
			(stroke
				(width 0.1)
				(type default)
			)
			(layer "F.Fab")
		)
		(fp_line
			(start -0.12065 0.2794)
			(end -0.12065 0.3048)
			(stroke
				(width 0.1)
				(type default)
			)
			(layer "F.Fab")
		)
		(fp_line
			(start 0.120396 0.2794)
			(end -0.12065 0.2794)
			(stroke
				(width 0.1)
				(type default)
			)
			(layer "F.Fab")
		)
		(fp_line
			(start -0.12065 -0.2794)
			(end 0.12065 -0.2794)
			(stroke
				(width 0.1)
				(type default)
			)
			(layer "F.Fab")
		)
		(fp_line
			(start 0.12065 -0.2794)
			(end 0.12065 -0.3048)
			(stroke
				(width 0.1)
				(type default)
			)
			(layer "F.Fab")
		)
		(fp_line
			(start 0.12065 -0.3048)
			(end 0.67945 -0.3048)
			(stroke
				(width 0.1)
				(type default)
			)
			(layer "F.Fab")
		)
		(fp_line
			(start 0.67945 -0.3048)
			(end 0.67945 0.3048)
			(stroke
				(width 0.1)
				(type default)
			)
			(layer "F.Fab")
		)
		(fp_line
			(start -0.67945 -0.305054)
			(end -0.12065 -0.305054)
			(stroke
				(width 0.1)
				(type default)
			)
			(layer "F.Fab")
		)
		(fp_line
			(start -0.12065 -0.305054)
			(end -0.12065 -0.2794)
			(stroke
				(width 0.1)
				(type default)
			)
			(layer "F.Fab")
		)
		(pad "1" smd circle
			(at -0.40005 0 270)
			(size 0 0)
			(layers "F.Cu" "F.Mask" "F.Paste")
			(net "LED_POSTCODE_1")
		)
		(pad "2" smd circle
			(at 0.40005 0 270)
			(size 0 0)
			(layers "F.Cu" "F.Mask" "F.Paste")
			(net "LED_POSTCODE_1_R")
		)
	)
	(footprint ""
		(layer "F.Cu")
		(at 51.71313 -97.168716 90)
		(property "Reference" "Q1"
			(at 3.237484 -1.483614 0)
			(unlocked yes)
			(layer "F.SilkS")
			(effects
				(font
					(size 0.7874 0.5842)
					(thickness 0.1524)
				)
				(justify left)
			)
		)
		(property "Value" ""
			(at 0 0 90)
			(layer "F.Fab")
			(effects
				(font
					(size 1.27 1.27)
				)
			)
		)
		(duplicate_pad_numbers_are_jumpers no)
		(fp_line
			(start 1.905 -1.651)
			(end 1.905 1.651)
			(stroke
				(width 0.1524)
				(type default)
			)
			(layer "F.SilkS")
		)
		(fp_line
			(start -1.905 -1.651)
			(end 1.905 -1.651)
			(stroke
				(width 0.1524)
				(type default)
			)
			(layer "F.SilkS")
		)
		(fp_line
			(start 1.905 1.651)
			(end -1.905 1.651)
			(stroke
				(width 0.1524)
				(type default)
			)
			(layer "F.SilkS")
		)
		(fp_line
			(start -1.905 1.651)
			(end -1.905 -1.651)
			(stroke
				(width 0.1524)
				(type default)
			)
			(layer "F.SilkS")
		)
		(fp_line
			(start 0.6985 -1.524)
			(end 0.6985 -0.219964)
			(stroke
				(width 0.1)
				(type default)
			)
			(layer "F.Fab")
		)
		(fp_line
			(start -0.649986 -1.524)
			(end 0.6985 -1.524)
			(stroke
				(width 0.1)
				(type default)
			)
			(layer "F.Fab")
		)
		(fp_line
			(start -0.649986 -1.169924)
			(end -0.649986 -1.524)
			(stroke
				(width 0.1)
				(type default)
			)
			(layer "F.Fab")
		)
		(fp_line
			(start -1.249934 -1.169924)
			(end -0.649986 -1.169924)
			(stroke
				(width 0.1)
				(type default)
			)
			(layer "F.Fab")
		)
		(fp_line
			(start -0.6985 -0.729996)
			(end -1.249934 -0.729996)
			(stroke
				(width 0.1)
				(type default)
			)
			(layer "F.Fab")
		)
		(fp_line
			(start -1.249934 -0.729996)
			(end -1.249934 -1.169924)
			(stroke
				(width 0.1)
				(type default)
			)
			(layer "F.Fab")
		)
		(fp_line
			(start 1.249934 -0.219964)
			(end 1.249934 0.219964)
			(stroke
				(width 0.1)
				(type default)
			)
			(layer "F.Fab")
		)
		(fp_line
			(start 0.6985 -0.219964)
			(end 1.249934 -0.219964)
			(stroke
				(width 0.1)
				(type default)
			)
			(layer "F.Fab")
		)
		(fp_line
			(start 1.249934 0.219964)
			(end 0.6985 0.219964)
			(stroke
				(width 0.1)
				(type default)
			)
			(layer "F.Fab")
		)
		(fp_line
			(start 0.6985 0.219964)
			(end 0.6985 1.524)
			(stroke
				(width 0.1)
				(type default)
			)
			(layer "F.Fab")
		)
		(fp_line
			(start -0.6985 0.729996)
			(end -0.6985 -0.729996)
			(stroke
				(width 0.1)
				(type default)
			)
			(layer "F.Fab")
		)
		(fp_line
			(start -1.249934 0.729996)
			(end -0.6985 0.729996)
			(stroke
				(width 0.1)
				(type default)
			)
			(layer "F.Fab")
		)
		(fp_line
			(start -0.649986 1.169924)
			(end -1.249934 1.169924)
			(stroke
				(width 0.1)
				(type default)
			)
			(layer "F.Fab")
		)
		(fp_line
			(start -1.249934 1.169924)
			(end -1.249934 0.729996)
			(stroke
				(width 0.1)
				(type default)
			)
			(layer "F.Fab")
		)
		(fp_line
			(start 0.6985 1.524)
			(end -0.649986 1.524)
			(stroke
				(width 0.1)
				(type default)
			)
			(layer "F.Fab")
		)
		(fp_line
			(start -0.649986 1.524)
			(end -0.649986 1.169924)
			(stroke
				(width 0.1)
				(type default)
			)
			(layer "F.Fab")
		)
		(pad "B" smd rect
			(at -1.1176 -1.016)
			(size 1.016 1.27)
			(layers "F.Cu" "F.Mask" "F.Paste")
			(net "BJT_Q3_C")
		)
		(pad "C" smd rect
			(at 1.1176 0)
			(size 1.016 1.27)
			(layers "F.Cu" "F.Mask" "F.Paste")
			(net "RST_BMC_EXTRST_R2_N")
		)
		(pad "E" smd rect
			(at -1.1176 1.016)
			(size 1.016 1.27)
			(layers "F.Cu" "F.Mask" "F.Paste")
			(net "GND")
		)
	)
)
